FILE_TYPE = CONNECTIVITY;
{Allegro Design Entry HDL 17.2-2016 S081 (4005846) 1/11/2022}
"PAGE_NUMBER" = 1;
0"NC";
END.
